(kicad_pcb
	(version 20260206)
	(generator "pcbnew")
	(generator_version "10.0")
	(general
		(thickness 1.6)
		(legacy_teardrops no)
	)
	(paper "A4")
	(title_block
		(title "04192023_DAF0TMB3IC0_F0TG_MB_C_brd_V02_OCP.brd")
		(comment 1 "Grand Teton / footprints 1842-1848 of 8354")
	)
	(layers
		(0 "F.Cu" signal "TOP")
		(4 "In1.Cu" signal "GND")
		(6 "In2.Cu" signal "IN1")
		(8 "In3.Cu" signal "GND1")
		(10 "In4.Cu" signal "IN2")
		(12 "In5.Cu" signal "GND2")
		(14 "In6.Cu" signal "IN3")
		(16 "In7.Cu" signal "GND3")
		(18 "In8.Cu" signal "VCC")
		(20 "In9.Cu" signal "VCC1")
		(22 "In10.Cu" signal "GND4")
		(24 "In11.Cu" signal "IN4")
		(26 "In12.Cu" signal "GND5")
		(28 "In13.Cu" signal "IN5")
		(30 "In14.Cu" signal "GND6")
		(32 "In15.Cu" signal "IN6")
		(34 "In16.Cu" signal "GND7")
		(2 "B.Cu" signal "BOTTOM")
		(9 "F.Adhes" user "F.Adhesive")
		(11 "B.Adhes" user "B.Adhesive")
		(13 "F.Paste" user "Package Geometry/Pastemask Top")
		(15 "B.Paste" user "Package Geometry/Pastemask Bottom")
		(5 "F.SilkS" user "Ref Des/Silkscreen Top")
		(7 "B.SilkS" user "Ref Des/Silkscreen Bottom")
		(1 "F.Mask" user "Board Geometry/Soldermask Top")
		(3 "B.Mask" user "Board Geometry/Soldermask Bottom")
		(17 "Dwgs.User" user "User.Drawings")
		(19 "Cmts.User" user "User.Comments")
		(21 "Eco1.User" user "User.Eco1")
		(23 "Eco2.User" user "User.Eco2")
		(25 "Edge.Cuts" user "Board Geometry/Outline")
		(27 "Margin" user)
		(31 "F.CrtYd" user "Package Geometry/Place Bound Top")
		(29 "B.CrtYd" user "Package Geometry/Place Bound Bottom")
		(35 "F.Fab" user "Ref Des/Assembly Top")
		(33 "B.Fab" user "Ref Des/Assembly Bottom")
	)
	(footprint ""
		(layer "F.Cu")
		(at 161.999676 -436.87238 90)
		(property "Reference" "C1707"
			(at 0 0 90)
			(layer "F.SilkS")
			(hide yes)
			(effects
				(font
					(size 1.27 1.27)
				)
			)
		)
		(property "Value" ""
			(at 0 0 90)
			(layer "F.Fab")
			(effects
				(font
					(size 1.27 1.27)
				)
			)
		)
		(duplicate_pad_numbers_are_jumpers no)
		(fp_line
			(start 0.7874 -0.4064)
			(end 0.7874 0.4064)
			(stroke
				(width 0.1524)
				(type default)
			)
			(layer "F.SilkS")
		)
		(fp_line
			(start -0.7874 -0.4064)
			(end 0.7874 -0.4064)
			(stroke
				(width 0.1524)
				(type default)
			)
			(layer "F.SilkS")
		)
		(fp_line
			(start 0.7874 0.4064)
			(end -0.7874 0.4064)
			(stroke
				(width 0.1524)
				(type default)
			)
			(layer "F.SilkS")
		)
		(fp_line
			(start -0.7874 0.4064)
			(end -0.7874 -0.4064)
			(stroke
				(width 0.1524)
				(type default)
			)
			(layer "F.SilkS")
		)
		(fp_line
			(start -0.12065 -0.305054)
			(end -0.12065 -0.2794)
			(stroke
				(width 0.1)
				(type default)
			)
			(layer "F.Fab")
		)
		(fp_line
			(start -0.67945 -0.305054)
			(end -0.12065 -0.305054)
			(stroke
				(width 0.1)
				(type default)
			)
			(layer "F.Fab")
		)
		(fp_line
			(start 0.67945 -0.3048)
			(end 0.67945 0.3048)
			(stroke
				(width 0.1)
				(type default)
			)
			(layer "F.Fab")
		)
		(fp_line
			(start 0.12065 -0.3048)
			(end 0.67945 -0.3048)
			(stroke
				(width 0.1)
				(type default)
			)
			(layer "F.Fab")
		)
		(fp_line
			(start 0.12065 -0.2794)
			(end 0.12065 -0.3048)
			(stroke
				(width 0.1)
				(type default)
			)
			(layer "F.Fab")
		)
		(fp_line
			(start -0.12065 -0.2794)
			(end 0.12065 -0.2794)
			(stroke
				(width 0.1)
				(type default)
			)
			(layer "F.Fab")
		)
		(fp_line
			(start 0.120396 0.2794)
			(end -0.12065 0.2794)
			(stroke
				(width 0.1)
				(type default)
			)
			(layer "F.Fab")
		)
		(fp_line
			(start -0.12065 0.2794)
			(end -0.12065 0.3048)
			(stroke
				(width 0.1)
				(type default)
			)
			(layer "F.Fab")
		)
		(fp_line
			(start 0.67945 0.3048)
			(end 0.120396 0.3048)
			(stroke
				(width 0.1)
				(type default)
			)
			(layer "F.Fab")
		)
		(fp_line
			(start 0.120396 0.3048)
			(end 0.120396 0.2794)
			(stroke
				(width 0.1)
				(type default)
			)
			(layer "F.Fab")
		)
		(fp_line
			(start -0.12065 0.3048)
			(end -0.67945 0.3048)
			(stroke
				(width 0.1)
				(type default)
			)
			(layer "F.Fab")
		)
		(fp_line
			(start -0.67945 0.3048)
			(end -0.67945 -0.305054)
			(stroke
				(width 0.1)
				(type default)
			)
			(layer "F.Fab")
		)
		(pad "1" smd circle
			(at -0.40005 0 90)
			(size 0 0)
			(layers "F.Cu" "F.Mask" "F.Paste")
			(net "P3V3_AUX")
		)
		(pad "2" smd circle
			(at 0.40005 0 90)
			(size 0 0)
			(layers "F.Cu" "F.Mask" "F.Paste")
			(net "GND")
		)
	)
	(footprint ""
		(layer "F.Cu")
		(at 170.213782 -390.33323)
		(property "Reference" "C401"
			(at 0 0 0)
			(layer "F.SilkS")
			(hide yes)
			(effects
				(font
					(size 1.27 1.27)
				)
			)
		)
		(property "Value" ""
			(at 0 0 0)
			(layer "F.Fab")
			(effects
				(font
					(size 1.27 1.27)
				)
			)
		)
		(duplicate_pad_numbers_are_jumpers no)
		(fp_line
			(start -1.524 -0.762)
			(end 1.524 -0.762)
			(stroke
				(width 0.1524)
				(type default)
			)
			(layer "F.SilkS")
		)
		(fp_line
			(start -1.524 0.762)
			(end -1.524 -0.762)
			(stroke
				(width 0.1524)
				(type default)
			)
			(layer "F.SilkS")
		)
		(fp_line
			(start 1.524 -0.762)
			(end 1.524 0.762)
			(stroke
				(width 0.1524)
				(type default)
			)
			(layer "F.SilkS")
		)
		(fp_line
			(start 1.524 0.762)
			(end -1.524 0.762)
			(stroke
				(width 0.1524)
				(type default)
			)
			(layer "F.SilkS")
		)
		(fp_line
			(start -1.1049 -0.724916)
			(end -1.1049 0.724916)
			(stroke
				(width 0.1)
				(type default)
			)
			(layer "F.Fab")
		)
		(fp_line
			(start -1.1049 0.724916)
			(end 1.1049 0.724916)
			(stroke
				(width 0.1)
				(type default)
			)
			(layer "F.Fab")
		)
		(fp_line
			(start 1.1049 -0.724916)
			(end -1.1049 -0.724916)
			(stroke
				(width 0.1)
				(type default)
			)
			(layer "F.Fab")
		)
		(fp_line
			(start 1.1049 0.724916)
			(end 1.1049 -0.724916)
			(stroke
				(width 0.1)
				(type default)
			)
			(layer "F.Fab")
		)
		(pad "1" smd rect
			(at -0.889 0 180)
			(size 1.016 1.27)
			(layers "F.Cu" "F.Mask" "F.Paste")
			(net "P0V9_CPU1_RT2_2A")
		)
		(pad "2" smd rect
			(at 0.889 0 180)
			(size 1.016 1.27)
			(layers "F.Cu" "F.Mask" "F.Paste")
			(net "GND")
		)
	)
	(footprint ""
		(layer "F.Cu")
		(at 164.719 -131.953 180)
		(property "Reference" "R482"
			(at 0 0 180)
			(layer "F.SilkS")
			(hide yes)
			(effects
				(font
					(size 1.27 1.27)
				)
			)
		)
		(property "Value" ""
			(at 0 0 180)
			(layer "F.Fab")
			(effects
				(font
					(size 1.27 1.27)
				)
			)
		)
		(duplicate_pad_numbers_are_jumpers no)
		(fp_line
			(start 0.7874 0.4064)
			(end -0.7874 0.4064)
			(stroke
				(width 0.1524)
				(type default)
			)
			(layer "F.SilkS")
		)
		(fp_line
			(start 0.7874 -0.4064)
			(end 0.7874 0.4064)
			(stroke
				(width 0.1524)
				(type default)
			)
			(layer "F.SilkS")
		)
		(fp_line
			(start -0.7874 0.4064)
			(end -0.7874 -0.4064)
			(stroke
				(width 0.1524)
				(type default)
			)
			(layer "F.SilkS")
		)
		(fp_line
			(start -0.7874 -0.4064)
			(end 0.7874 -0.4064)
			(stroke
				(width 0.1524)
				(type default)
			)
			(layer "F.SilkS")
		)
		(fp_line
			(start 0.67945 0.3048)
			(end 0.120396 0.3048)
			(stroke
				(width 0.1)
				(type default)
			)
			(layer "F.Fab")
		)
		(fp_line
			(start 0.67945 -0.3048)
			(end 0.67945 0.3048)
			(stroke
				(width 0.1)
				(type default)
			)
			(layer "F.Fab")
		)
		(fp_line
			(start 0.12065 -0.2794)
			(end 0.12065 -0.3048)
			(stroke
				(width 0.1)
				(type default)
			)
			(layer "F.Fab")
		)
		(fp_line
			(start 0.12065 -0.3048)
			(end 0.67945 -0.3048)
			(stroke
				(width 0.1)
				(type default)
			)
			(layer "F.Fab")
		)
		(fp_line
			(start 0.120396 0.3048)
			(end 0.120396 0.2794)
			(stroke
				(width 0.1)
				(type default)
			)
			(layer "F.Fab")
		)
		(fp_line
			(start 0.120396 0.2794)
			(end -0.12065 0.2794)
			(stroke
				(width 0.1)
				(type default)
			)
			(layer "F.Fab")
		)
		(fp_line
			(start -0.12065 0.3048)
			(end -0.67945 0.3048)
			(stroke
				(width 0.1)
				(type default)
			)
			(layer "F.Fab")
		)
		(fp_line
			(start -0.12065 0.2794)
			(end -0.12065 0.3048)
			(stroke
				(width 0.1)
				(type default)
			)
			(layer "F.Fab")
		)
		(fp_line
			(start -0.12065 -0.2794)
			(end 0.12065 -0.2794)
			(stroke
				(width 0.1)
				(type default)
			)
			(layer "F.Fab")
		)
		(fp_line
			(start -0.12065 -0.305054)
			(end -0.12065 -0.2794)
			(stroke
				(width 0.1)
				(type default)
			)
			(layer "F.Fab")
		)
		(fp_line
			(start -0.67945 0.3048)
			(end -0.67945 -0.305054)
			(stroke
				(width 0.1)
				(type default)
			)
			(layer "F.Fab")
		)
		(fp_line
			(start -0.67945 -0.305054)
			(end -0.12065 -0.305054)
			(stroke
				(width 0.1)
				(type default)
			)
			(layer "F.Fab")
		)
		(pad "1" smd circle
			(at -0.40005 0 180)
			(size 0 0)
			(layers "F.Cu" "F.Mask" "F.Paste")
			(net "PWRGD_P5V_R")
		)
		(pad "2" smd circle
			(at 0.40005 0 180)
			(size 0 0)
			(layers "F.Cu" "F.Mask" "F.Paste")
			(net "PWRGD_P5V_R1")
		)
	)
	(footprint ""
		(layer "F.Cu")
		(at 322.837048 -44.716954)
		(property "Reference" "R3861"
			(at 0 0 0)
			(layer "F.SilkS")
			(hide yes)
			(effects
				(font
					(size 1.27 1.27)
				)
			)
		)
		(property "Value" ""
			(at 0 0 0)
			(layer "F.Fab")
			(effects
				(font
					(size 1.27 1.27)
				)
			)
		)
		(duplicate_pad_numbers_are_jumpers no)
		(fp_line
			(start -0.7874 -0.4064)
			(end 0.7874 -0.4064)
			(stroke
				(width 0.1524)
				(type default)
			)
			(layer "F.SilkS")
		)
		(fp_line
			(start -0.7874 0.4064)
			(end -0.7874 -0.4064)
			(stroke
				(width 0.1524)
				(type default)
			)
			(layer "F.SilkS")
		)
		(fp_line
			(start 0.7874 -0.4064)
			(end 0.7874 0.4064)
			(stroke
				(width 0.1524)
				(type default)
			)
			(layer "F.SilkS")
		)
		(fp_line
			(start 0.7874 0.4064)
			(end -0.7874 0.4064)
			(stroke
				(width 0.1524)
				(type default)
			)
			(layer "F.SilkS")
		)
		(fp_line
			(start -0.67945 -0.305054)
			(end -0.12065 -0.305054)
			(stroke
				(width 0.1)
				(type default)
			)
			(layer "F.Fab")
		)
		(fp_line
			(start -0.67945 0.3048)
			(end -0.67945 -0.305054)
			(stroke
				(width 0.1)
				(type default)
			)
			(layer "F.Fab")
		)
		(fp_line
			(start -0.12065 -0.305054)
			(end -0.12065 -0.2794)
			(stroke
				(width 0.1)
				(type default)
			)
			(layer "F.Fab")
		)
		(fp_line
			(start -0.12065 -0.2794)
			(end 0.12065 -0.2794)
			(stroke
				(width 0.1)
				(type default)
			)
			(layer "F.Fab")
		)
		(fp_line
			(start -0.12065 0.2794)
			(end -0.12065 0.3048)
			(stroke
				(width 0.1)
				(type default)
			)
			(layer "F.Fab")
		)
		(fp_line
			(start -0.12065 0.3048)
			(end -0.67945 0.3048)
			(stroke
				(width 0.1)
				(type default)
			)
			(layer "F.Fab")
		)
		(fp_line
			(start 0.120396 0.2794)
			(end -0.12065 0.2794)
			(stroke
				(width 0.1)
				(type default)
			)
			(layer "F.Fab")
		)
		(fp_line
			(start 0.120396 0.3048)
			(end 0.120396 0.2794)
			(stroke
				(width 0.1)
				(type default)
			)
			(layer "F.Fab")
		)
		(fp_line
			(start 0.12065 -0.3048)
			(end 0.67945 -0.3048)
			(stroke
				(width 0.1)
				(type default)
			)
			(layer "F.Fab")
		)
		(fp_line
			(start 0.12065 -0.2794)
			(end 0.12065 -0.3048)
			(stroke
				(width 0.1)
				(type default)
			)
			(layer "F.Fab")
		)
		(fp_line
			(start 0.67945 -0.3048)
			(end 0.67945 0.3048)
			(stroke
				(width 0.1)
				(type default)
			)
			(layer "F.Fab")
		)
		(fp_line
			(start 0.67945 0.3048)
			(end 0.120396 0.3048)
			(stroke
				(width 0.1)
				(type default)
			)
			(layer "F.Fab")
		)
		(pad "1" smd rect
			(at -0.40005 0 180)
			(size 0.4572 0.508)
			(layers "F.Cu" "F.Mask" "F.Paste")
			(net "P12V_OCP_V3_2_ISENSE_MAM_TIC")
		)
		(pad "2" smd rect
			(at 0.40005 0 180)
			(size 0.4572 0.508)
			(layers "F.Cu" "F.Mask" "F.Paste")
			(net "P12V_OCP_V3_2_ISENSE_TIC")
		)
	)
	(footprint ""
		(layer "F.Cu")
		(at 140.3096 -401.866608 90)
		(property "Reference" "C7006"
			(at 0 0 90)
			(layer "F.SilkS")
			(hide yes)
			(effects
				(font
					(size 1.27 1.27)
				)
			)
		)
		(property "Value" ""
			(at 0 0 90)
			(layer "F.Fab")
			(effects
				(font
					(size 1.27 1.27)
				)
			)
		)
		(duplicate_pad_numbers_are_jumpers no)
		(fp_line
			(start 1.524 -0.762)
			(end 1.524 0.762)
			(stroke
				(width 0.1524)
				(type default)
			)
			(layer "F.SilkS")
		)
		(fp_line
			(start -1.524 -0.762)
			(end 1.524 -0.762)
			(stroke
				(width 0.1524)
				(type default)
			)
			(layer "F.SilkS")
		)
		(fp_line
			(start 1.524 0.762)
			(end -1.524 0.762)
			(stroke
				(width 0.1524)
				(type default)
			)
			(layer "F.SilkS")
		)
		(fp_line
			(start -1.524 0.762)
			(end -1.524 -0.762)
			(stroke
				(width 0.1524)
				(type default)
			)
			(layer "F.SilkS")
		)
		(fp_line
			(start 1.1049 -0.724916)
			(end -1.1049 -0.724916)
			(stroke
				(width 0.1)
				(type default)
			)
			(layer "F.Fab")
		)
		(fp_line
			(start -1.1049 -0.724916)
			(end -1.1049 0.724916)
			(stroke
				(width 0.1)
				(type default)
			)
			(layer "F.Fab")
		)
		(fp_line
			(start 1.1049 0.724916)
			(end 1.1049 -0.724916)
			(stroke
				(width 0.1)
				(type default)
			)
			(layer "F.Fab")
		)
		(fp_line
			(start -1.1049 0.724916)
			(end 1.1049 0.724916)
			(stroke
				(width 0.1)
				(type default)
			)
			(layer "F.Fab")
		)
		(pad "1" smd rect
			(at -0.889 0 270)
			(size 1.016 1.27)
			(layers "F.Cu" "F.Mask" "F.Paste")
			(net "P0V9_CPU1_RT_2D")
		)
		(pad "2" smd rect
			(at 0.889 0 270)
			(size 1.016 1.27)
			(layers "F.Cu" "F.Mask" "F.Paste")
			(net "GND")
		)
	)
	(footprint ""
		(layer "F.Cu")
		(at 9.271 -73.279)
		(property "Reference" "R8015"
			(at 0 0 0)
			(layer "F.SilkS")
			(hide yes)
			(effects
				(font
					(size 1.27 1.27)
				)
			)
		)
		(property "Value" ""
			(at 0 0 0)
			(layer "F.Fab")
			(effects
				(font
					(size 1.27 1.27)
				)
			)
		)
		(duplicate_pad_numbers_are_jumpers no)
		(fp_line
			(start -0.7874 -0.4064)
			(end 0.7874 -0.4064)
			(stroke
				(width 0.1524)
				(type default)
			)
			(layer "F.SilkS")
		)
		(fp_line
			(start -0.7874 0.4064)
			(end -0.7874 -0.4064)
			(stroke
				(width 0.1524)
				(type default)
			)
			(layer "F.SilkS")
		)
		(fp_line
			(start 0.7874 -0.4064)
			(end 0.7874 0.4064)
			(stroke
				(width 0.1524)
				(type default)
			)
			(layer "F.SilkS")
		)
		(fp_line
			(start 0.7874 0.4064)
			(end -0.7874 0.4064)
			(stroke
				(width 0.1524)
				(type default)
			)
			(layer "F.SilkS")
		)
		(fp_line
			(start -0.67945 -0.305054)
			(end -0.12065 -0.305054)
			(stroke
				(width 0.1)
				(type default)
			)
			(layer "F.Fab")
		)
		(fp_line
			(start -0.67945 0.3048)
			(end -0.67945 -0.305054)
			(stroke
				(width 0.1)
				(type default)
			)
			(layer "F.Fab")
		)
		(fp_line
			(start -0.12065 -0.305054)
			(end -0.12065 -0.2794)
			(stroke
				(width 0.1)
				(type default)
			)
			(layer "F.Fab")
		)
		(fp_line
			(start -0.12065 -0.2794)
			(end 0.12065 -0.2794)
			(stroke
				(width 0.1)
				(type default)
			)
			(layer "F.Fab")
		)
		(fp_line
			(start -0.12065 0.2794)
			(end -0.12065 0.3048)
			(stroke
				(width 0.1)
				(type default)
			)
			(layer "F.Fab")
		)
		(fp_line
			(start -0.12065 0.3048)
			(end -0.67945 0.3048)
			(stroke
				(width 0.1)
				(type default)
			)
			(layer "F.Fab")
		)
		(fp_line
			(start 0.120396 0.2794)
			(end -0.12065 0.2794)
			(stroke
				(width 0.1)
				(type default)
			)
			(layer "F.Fab")
		)
		(fp_line
			(start 0.120396 0.3048)
			(end 0.120396 0.2794)
			(stroke
				(width 0.1)
				(type default)
			)
			(layer "F.Fab")
		)
		(fp_line
			(start 0.12065 -0.3048)
			(end 0.67945 -0.3048)
			(stroke
				(width 0.1)
				(type default)
			)
			(layer "F.Fab")
		)
		(fp_line
			(start 0.12065 -0.2794)
			(end 0.12065 -0.3048)
			(stroke
				(width 0.1)
				(type default)
			)
			(layer "F.Fab")
		)
		(fp_line
			(start 0.67945 -0.3048)
			(end 0.67945 0.3048)
			(stroke
				(width 0.1)
				(type default)
			)
			(layer "F.Fab")
		)
		(fp_line
			(start 0.67945 0.3048)
			(end 0.120396 0.3048)
			(stroke
				(width 0.1)
				(type default)
			)
			(layer "F.Fab")
		)
		(pad "1" smd circle
			(at -0.40005 0)
			(size 0 0)
			(layers "F.Cu" "F.Mask" "F.Paste")
			(net "OCP_V3_2_PRSNT01_R_N")
		)
		(pad "2" smd circle
			(at 0.40005 0)
			(size 0 0)
			(layers "F.Cu" "F.Mask" "F.Paste")
			(net "OCP_V3_2_PRSNT01_R1_N")
		)
	)
	(footprint ""
		(layer "F.Cu")
		(at 185.928762 -26.788872 180)
		(property "Reference" "PR4008"
			(at 0 0 180)
			(layer "F.SilkS")
			(hide yes)
			(effects
				(font
					(size 1.27 1.27)
				)
			)
		)
		(property "Value" ""
			(at 0 0 180)
			(layer "F.Fab")
			(effects
				(font
					(size 1.27 1.27)
				)
			)
		)
		(duplicate_pad_numbers_are_jumpers no)
		(fp_line
			(start 0.7874 0.4064)
			(end -0.7874 0.4064)
			(stroke
				(width 0.1524)
				(type default)
			)
			(layer "F.SilkS")
		)
		(fp_line
			(start 0.7874 -0.4064)
			(end 0.7874 0.4064)
			(stroke
				(width 0.1524)
				(type default)
			)
			(layer "F.SilkS")
		)
		(fp_line
			(start -0.7874 0.4064)
			(end -0.7874 -0.4064)
			(stroke
				(width 0.1524)
				(type default)
			)
			(layer "F.SilkS")
		)
		(fp_line
			(start -0.7874 -0.4064)
			(end 0.7874 -0.4064)
			(stroke
				(width 0.1524)
				(type default)
			)
			(layer "F.SilkS")
		)
		(fp_line
			(start 0.67945 0.3048)
			(end 0.120396 0.3048)
			(stroke
				(width 0.1)
				(type default)
			)
			(layer "F.Fab")
		)
		(fp_line
			(start 0.67945 -0.3048)
			(end 0.67945 0.3048)
			(stroke
				(width 0.1)
				(type default)
			)
			(layer "F.Fab")
		)
		(fp_line
			(start 0.12065 -0.2794)
			(end 0.12065 -0.3048)
			(stroke
				(width 0.1)
				(type default)
			)
			(layer "F.Fab")
		)
		(fp_line
			(start 0.12065 -0.3048)
			(end 0.67945 -0.3048)
			(stroke
				(width 0.1)
				(type default)
			)
			(layer "F.Fab")
		)
		(fp_line
			(start 0.120396 0.3048)
			(end 0.120396 0.2794)
			(stroke
				(width 0.1)
				(type default)
			)
			(layer "F.Fab")
		)
		(fp_line
			(start 0.120396 0.2794)
			(end -0.12065 0.2794)
			(stroke
				(width 0.1)
				(type default)
			)
			(layer "F.Fab")
		)
		(fp_line
			(start -0.12065 0.3048)
			(end -0.67945 0.3048)
			(stroke
				(width 0.1)
				(type default)
			)
			(layer "F.Fab")
		)
		(fp_line
			(start -0.12065 0.2794)
			(end -0.12065 0.3048)
			(stroke
				(width 0.1)
				(type default)
			)
			(layer "F.Fab")
		)
		(fp_line
			(start -0.12065 -0.2794)
			(end 0.12065 -0.2794)
			(stroke
				(width 0.1)
				(type default)
			)
			(layer "F.Fab")
		)
		(fp_line
			(start -0.12065 -0.305054)
			(end -0.12065 -0.2794)
			(stroke
				(width 0.1)
				(type default)
			)
			(layer "F.Fab")
		)
		(fp_line
			(start -0.67945 0.3048)
			(end -0.67945 -0.305054)
			(stroke
				(width 0.1)
				(type default)
			)
			(layer "F.Fab")
		)
		(fp_line
			(start -0.67945 -0.305054)
			(end -0.12065 -0.305054)
			(stroke
				(width 0.1)
				(type default)
			)
			(layer "F.Fab")
		)
		(pad "1" smd circle
			(at -0.40005 0 180)
			(size 0 0)
			(layers "F.Cu" "F.Mask" "F.Paste")
			(net "P12V_SCM_SENSE")
		)
		(pad "2" smd circle
			(at 0.40005 0 180)
			(size 0 0)
			(layers "F.Cu" "F.Mask" "F.Paste")
			(net "GND")
		)
	)
)
